# S9S_MB_2U (Grand Teton) — schematic netlist excerpt (pin names and nets, part order shuffled) for the footprints in the layout excerpt that follows; sources: Cadence DE-HDL packaged netlist, KiCad conversion of 03242023_DA0F0TMBIJ0_F0T_Motherboard_J_brd_V01_OCP.brd

PU69_P0_1  ISL99390FRZTR5935  ISL99390FRZ-TR5935 IC  pkg QFN21_6X5XB  page 271
  VOS  = PVCCFA_EHV_FIVRA_CPU0_VOS1
  AGND  = GND
  VCC  = PVCCFA_EHV_FIVRA_CPU0_VDD1
  PVCC  = PVCCFA_EHV_FIVRA_CPU0_PVCC1
  PGND1  = GND
  GL1  = NC
  PGND2  = GND
  SW  = SW_PVCCFA_EHV_FIVRA_CPU0_SW1
  VIN1  = SW_P12V_PVCCFA_EHV_FIVRA_CPU0_R
  VIN2  = SW_P12V_PVCCFA_EHV_FIVRA_CPU0_R
  DNC  = NC
  PHASE  = SW_PVCCFA_EHV_FIVRA_CPU0_BOOTR1
  BOOT  = SW_PVCCFA_EHV_FIVRA_CPU0_BOOT1
  PWM  = PVCCFA_EHV_FIVRA_CPU0_PWM1
  EN  = PVCCFA_EHV_FIVRA_CPU0_VDD1
  TOUT_FLT  = PVCCFA_EHV_FIVRA_CPU0_BTSEN
  LSET  = PVCCFA_EHV_FIVRA_CPU0_LSET1
  IOUT  = PVCCFA_EHV_FIVRA_CPU0_IMON1
  REFIN  = PVCCIN_CPU0_VREF
  PGND3  = GND
  GL2  = NC

(kicad_pcb
	(version 20260206)
	(generator "pcbnew")
	(generator_version "10.0")
	(general
		(thickness 1.6)
		(legacy_teardrops no)
	)
	(paper "A4")
	(title_block
		(title "03242023_DA0F0TMBIJ0_F0T_Motherboard_J_brd_V01_OCP.brd")
		(comment 1 "Grand Teton / footprints 3835-3835 of 6105")
	)
	(layers
		(0 "F.Cu" signal "TOP")
		(4 "In1.Cu" signal "GND")
		(6 "In2.Cu" signal "IN1")
		(8 "In3.Cu" signal "GND1")
		(10 "In4.Cu" signal "IN2")
		(12 "In5.Cu" signal "GND2")
		(14 "In6.Cu" signal "IN3")
		(16 "In7.Cu" signal "GND3")
		(18 "In8.Cu" signal "VCC")
		(20 "In9.Cu" signal "VCC1")
		(22 "In10.Cu" signal "GND4")
		(24 "In11.Cu" signal "IN4")
		(26 "In12.Cu" signal "GND5")
		(28 "In13.Cu" signal "IN5")
		(30 "In14.Cu" signal "GND6")
		(32 "In15.Cu" signal "IN6")
		(34 "In16.Cu" signal "GND7")
		(2 "B.Cu" signal "BOTTOM")
		(9 "F.Adhes" user "F.Adhesive")
		(11 "B.Adhes" user "B.Adhesive")
		(13 "F.Paste" user "Package Geometry/Pastemask Top")
		(15 "B.Paste" user "Package Geometry/Pastemask Bottom")
		(5 "F.SilkS" user "Ref Des/Silkscreen Top")
		(7 "B.SilkS" user "Ref Des/Silkscreen Bottom")
		(1 "F.Mask" user "Board Geometry/Soldermask Top")
		(3 "B.Mask" user "Board Geometry/Soldermask Bottom")
		(17 "Dwgs.User" user "User.Drawings")
		(19 "Cmts.User" user "User.Comments")
		(21 "Eco1.User" user "User.Eco1")
		(23 "Eco2.User" user "User.Eco2")
		(25 "Edge.Cuts" user "Board Geometry/Outline")
		(27 "Margin" user)
		(31 "F.CrtYd" user "Package Geometry/Place Bound Top")
		(29 "B.CrtYd" user "Package Geometry/Place Bound Bottom")
		(35 "F.Fab" user "Ref Des/Assembly Top")
		(33 "B.Fab" user "Ref Des/Assembly Bottom")
	)
	(footprint ""
		(layer "F.Cu")
		(at 416.160458 -362.087668)
		(property "Reference" "PU69_P0_1"
			(at -7.134098 -6.55193 0)
			(unlocked yes)
			(layer "F.SilkS")
			(effects
				(font
					(size 0.7874 0.5842)
					(thickness 0.1524)
				)
				(justify left)
			)
		)
		(property "Value" ""
			(at 0 0 0)
			(layer "F.Fab")
			(effects
				(font
					(size 1.27 1.27)
				)
			)
		)
		(duplicate_pad_numbers_are_jumpers no)
		(fp_line
			(start -2.500122 -2.999994)
			(end -2.24409 -2.999994)
			(stroke
				(width 0.1524)
				(type default)
			)
			(layer "F.SilkS")
		)
		(fp_line
			(start -2.500122 -2.529078)
			(end -2.500122 -2.999994)
			(stroke
				(width 0.1524)
				(type default)
			)
			(layer "F.SilkS")
		)
		(fp_line
			(start -2.500122 0.6604)
			(end -2.500122 0.229108)
			(stroke
				(width 0.1524)
				(type default)
			)
			(layer "F.SilkS")
		)
		(fp_line
			(start -2.500122 2.999994)
			(end -2.500122 2.339594)
			(stroke
				(width 0.1524)
				(type default)
			)
			(layer "F.SilkS")
		)
		(fp_line
			(start -2.2987 2.999994)
			(end -2.500122 2.999994)
			(stroke
				(width 0.1524)
				(type default)
			)
			(layer "F.SilkS")
		)
		(fp_line
			(start 2.31394 -2.999994)
			(end 2.500122 -2.999994)
			(stroke
				(width 0.1524)
				(type default)
			)
			(layer "F.SilkS")
		)
		(fp_line
			(start 2.500122 -2.999994)
			(end 2.500122 -2.44348)
			(stroke
				(width 0.1524)
				(type default)
			)
			(layer "F.SilkS")
		)
		(fp_line
			(start 2.500122 2.339594)
			(end 2.500122 2.999994)
			(stroke
				(width 0.1524)
				(type default)
			)
			(layer "F.SilkS")
		)
		(fp_line
			(start 2.500122 2.999994)
			(end 2.2987 2.999994)
			(stroke
				(width 0.1524)
				(type default)
			)
			(layer "F.SilkS")
		)
		(fp_poly
			(pts
				(xy -2.16916 -3.647694) (xy -2.67716 -2.631694) (xy -3.18516 -3.647694)
			)
			(stroke
				(width 0)
				(type default)
			)
			(fill yes)
			(layer "F.SilkS")
		)
		(fp_line
			(start -2.500122 -2.999994)
			(end 2.500122 -2.999994)
			(stroke
				(width 0.1)
				(type default)
			)
			(layer "F.Fab")
		)
		(fp_line
			(start -2.500122 2.999994)
			(end -2.500122 -2.999994)
			(stroke
				(width 0.1)
				(type default)
			)
			(layer "F.Fab")
		)
		(fp_line
			(start 2.500122 -2.999994)
			(end 2.500122 2.999994)
			(stroke
				(width 0.1)
				(type default)
			)
			(layer "F.Fab")
		)
		(fp_line
			(start 2.500122 2.999994)
			(end -2.500122 2.999994)
			(stroke
				(width 0.1)
				(type default)
			)
			(layer "F.Fab")
		)
		(fp_poly
			(pts
				(xy -4.218432 -2.783078) (xy -4.218432 -1.767078) (xy -3.202432 -2.275078)
			)
			(stroke
				(width 0)
				(type default)
			)
			(fill yes)
			(layer "F.Fab")
		)
		(pad "1" smd rect
			(at -2.400046 -2.275078 90)
			(size 0.2286 0.6096)
			(layers "F.Cu" "F.Mask" "F.Paste")
			(net "PVCCFA_EHV_FIVRA_CPU0_VOS1")
		)
		(pad "2" smd rect
			(at -2.400046 -1.82499 90)
			(size 0.2286 0.6096)
			(layers "F.Cu" "F.Mask" "F.Paste")
			(net "GND")
		)
		(pad "3" smd rect
			(at -2.400046 -1.374902 90)
			(size 0.2286 0.6096)
			(layers "F.Cu" "F.Mask" "F.Paste")
			(net "PVCCFA_EHV_FIVRA_CPU0_VDD1")
		)
		(pad "4" smd rect
			(at -2.400046 -0.925068 90)
			(size 0.2286 0.6096)
			(layers "F.Cu" "F.Mask" "F.Paste")
			(net "PVCCFA_EHV_FIVRA_CPU0_PVCC1")
		)
		(pad "5" smd rect
			(at -2.400046 -0.47498 90)
			(size 0.2286 0.6096)
			(layers "F.Cu" "F.Mask" "F.Paste")
			(net "GND")
		)
		(pad "6" smd rect
			(at -2.400046 -0.024892 90)
			(size 0.2286 0.6096)
			(layers "F.Cu" "F.Mask" "F.Paste")
			(net "Net_8517")
		)
		(pad "7_9-20_24" smd circle
			(at 0 1.150112 90)
			(size 0 0)
			(layers "F.Cu" "F.Mask" "F.Paste")
			(net "GND")
		)
		(pad "10_19" smd rect
			(at 0 2.899918 90)
			(size 0.6096 4.318)
			(layers "F.Cu" "F.Mask" "F.Paste")
			(net "SW_PVCCFA_EHV_FIVRA_CPU0_SW1")
		)
		(pad "25_29" smd rect
			(at 1.549908 -1.279906 270)
			(size 2.0574 2.3114)
			(layers "F.Cu" "F.Mask" "F.Paste")
			(net "SW_P12V_PVCCFA_EHV_FIVRA_CPU0_R")
		)
		(pad "30" smd rect
			(at 2.05994 -2.899918)
			(size 0.2286 0.6096)
			(layers "F.Cu" "F.Mask" "F.Paste")
			(net "SW_P12V_PVCCFA_EHV_FIVRA_CPU0_R")
		)
		(pad "31" smd rect
			(at 1.610106 -2.899918)
			(size 0.2286 0.6096)
			(layers "F.Cu" "F.Mask" "F.Paste")
			(net "Net_8518")
		)
		(pad "32" smd rect
			(at 1.160018 -2.899918)
			(size 0.2286 0.6096)
			(layers "F.Cu" "F.Mask" "F.Paste")
			(net "SW_PVCCFA_EHV_FIVRA_CPU0_BOOTR1")
		)
		(pad "33" smd rect
			(at 0.70993 -2.899918)
			(size 0.2286 0.6096)
			(layers "F.Cu" "F.Mask" "F.Paste")
			(net "SW_PVCCFA_EHV_FIVRA_CPU0_BOOT1")
		)
		(pad "34" smd rect
			(at 0.260096 -2.899918)
			(size 0.2286 0.6096)
			(layers "F.Cu" "F.Mask" "F.Paste")
			(net "PVCCFA_EHV_FIVRA_CPU0_PWM1")
		)
		(pad "35" smd rect
			(at -0.189992 -2.899918)
			(size 0.2286 0.6096)
			(layers "F.Cu" "F.Mask" "F.Paste")
			(net "PVCCFA_EHV_FIVRA_CPU0_VDD1")
		)
		(pad "36" smd rect
			(at -0.64008 -2.899918)
			(size 0.2286 0.6096)
			(layers "F.Cu" "F.Mask" "F.Paste")
			(net "PVCCFA_EHV_FIVRA_CPU0_BTSEN")
		)
		(pad "37" smd rect
			(at -1.089914 -2.899918)
			(size 0.2286 0.6096)
			(layers "F.Cu" "F.Mask" "F.Paste")
			(net "PVCCFA_EHV_FIVRA_CPU0_LSET1")
		)
		(pad "38" smd rect
			(at -1.540002 -2.899918)
			(size 0.2286 0.6096)
			(layers "F.Cu" "F.Mask" "F.Paste")
			(net "PVCCFA_EHV_FIVRA_CPU0_IMON1")
		)
		(pad "39" smd rect
			(at -1.99009 -2.899918)
			(size 0.2286 0.6096)
			(layers "F.Cu" "F.Mask" "F.Paste")
			(net "PVCCIN_CPU0_VREF")
		)
		(pad "40" smd rect
			(at -0.87503 -1.27508)
			(size 1.7526 1.9558)
			(layers "F.Cu" "F.Mask" "F.Paste")
			(net "GND")
		)
		(pad "41" smd rect
			(at -1.525016 0.249936 270)
			(size 0.3048 0.4572)
			(layers "F.Cu" "F.Mask" "F.Paste")
			(net "Net_8516")
		)
		(zone
			(layer "F.Cu")
			(hatch none 0.5)
			(connect_pads
				(clearance 0)
			)
			(min_thickness 0.25)
			(keepout
				(tracks not_allowed)
				(vias allowed)
				(pads allowed)
				(copperpour not_allowed)
				(footprints allowed)
			)
			(placement
				(enabled no)
				(sheetname "")
			)
			(fill
				(thermal_gap 0.5)
				(thermal_bridge_width 0.5)
				(island_removal_mode 0)
			)
			(polygon
				(pts
					(xy 413.660336 -359.087674) (xy 413.660336 -359.836974) (xy 418.66058 -359.836974) (xy 418.66058 -359.087674)
					(xy 418.370258 -359.087674) (xy 418.370258 -359.54335) (xy 413.950658 -359.54335) (xy 413.950658 -359.087674)
				)
			)
		)
		(zone
			(layer "F.Cu")
			(hatch none 0.5)
			(connect_pads
				(clearance 0)
			)
			(min_thickness 0.25)
			(keepout
				(tracks not_allowed)
				(vias allowed)
				(pads allowed)
				(copperpour not_allowed)
				(footprints allowed)
			)
			(placement
				(enabled no)
				(sheetname "")
			)
			(fill
				(thermal_gap 0.5)
				(thermal_bridge_width 0.5)
				(island_removal_mode 0)
			)
			(polygon
				(pts
					(xy 414.116012 -362.359956) (xy 414.358328 -362.359956) (xy 414.358328 -362.334048) (xy 415.174684 -362.334048)
					(xy 415.174684 -362.009182) (xy 415.209736 -362.009182) (xy 415.209736 -361.387644) (xy 415.16046 -361.338368)
					(xy 413.660336 -361.338368) (xy 413.660336 -361.79506) (xy 414.356042 -361.79506) (xy 414.356042 -361.634532)
					(xy 414.914842 -361.634532) (xy 414.914842 -362.040932) (xy 414.356042 -362.040932) (xy 414.356042 -361.82046)
					(xy 413.660336 -361.82046) (xy 413.660336 -361.94746) (xy 414.116012 -361.94746)
				)
			)
		)
	)
)
